#ISCELL
  pure_quanta quanta_title_block_c *
  *
#CELL
  pure_quanta conn3_g800lq305005fthr *
  page156_i1
#CELL
  pure_quanta q_res *
  page156_i10
#ISCELL
  pure_quanta_power universal_gnd *
  page156_i2
#CELL
  pure_quanta ncp698sq15t1g *
  page156_i22
#ISCELL
  pure_quanta_power universal_gnd *
  page156_i23
#CELL
  pure_quanta q_res *
  page156_i24
#ISCELL
  pure_quanta_power universal_power *
  page156_i25
#CELL
  pure_quanta q_cap *
  page156_i26
#CELL
  pure_quanta q_cap *
  page156_i27
#ISCELL
  pure_quanta_power universal_gnd *
  page156_i28
#ISCELL
  pure_quanta_power universal_power *
  page156_i29
#ISCELL
  pure_quanta_power universal_power *
  page156_i3
#CELL
  pure_quanta schottky_dual_12a_3c *
  page156_i30
#CELL
  pure_quanta q_res *
  page156_i32
#CELL
  pure_quanta q_cap *
  page156_i35
#ISCELL
  pure_quanta_power universal_gnd *
  page156_i36
#CELL
  pure_quanta q_res *
  page156_i37
#ISCELL
  standard offpage *
  page156_i38
#CELL
  pure_quanta conn2_aaabat029p15 *
  page156_i39
#CELL
  pure_quanta q_cap *
  page156_i4
#ISCELL
  pure_quanta_power gnd *
  page156_i40
#CELL
  pure_quanta mosfet_dual_6p *
  page156_i41
#ISCELL
  pure_quanta_power universal_gnd *
  page156_i42
#ISCELL
  pure_quanta_power universal_gnd *
  page156_i43
#CELL
  pure_quanta tp *
  page156_i45
#CELL
  pure_quanta tp *
  page156_i46
#ISCELL
  pure_quanta_power universal_gnd *
  page156_i5
#CELL
  pure_quanta q_cap *
  page156_i6
#ISCELL
  pure_quanta_power universal_gnd *
  page156_i7
